#ISCELL
  mstr_misc dns *
  *
#ISCELL
  mstr_symbols bom_note *
  *
#ISCELL
  mstr_symbols cad_note *
  *
#ISCELL
  mstr_symbols design_note *
  *
#ISCELL
  mstr_symbols intel_corp_bpage *
  *
#CELL
  mstr_discrete res *
  page137_i11
#ISCELL
  mstr_standard offpage *
  page137_i123
#ISCELL
  mstr_standard offpage *
  page137_i124
#ISCELL
  mstr_standard offpage *
  page137_i126
#CELL
  mstr_conn conn12_c73564003 *
  page137_i128
#ISCELL
  mstr_standard offpage *
  page137_i129
#CELL
  mstr_discrete res *
  page137_i13
#CELL
  dev_discrete cap_a *
  page137_i14
#CELL
  mstr_discrete res *
  page137_i15
#ISCELL
  mstr_symbols gnd *
  page137_i16
#ISCELL
  mstr_standard offpage *
  page137_i17
#CELL
  mstr_discrete res *
  page137_i19
#CELL
  dev_discrete cap_a *
  page137_i20
#ISCELL
  mstr_symbols gnd *
  page137_i21
#CELL
  mstr_discrete res *
  page137_i67
#ISCELL
  mstr_symbols p3v3_stby *
  page137_i68
#CELL
  mstr_discrete res *
  page137_i69
#ISCELL
  mstr_symbols gnd *
  page137_i70
#ISCELL
  mstr_symbols p3v3_rtc_stby *
  page137_i78
#ISCELL
  mstr_symbols p3v3_rtc_stby *
  page137_i79
